(kicad_pcb
	(version 20260206)
	(generator "pcbnew")
	(generator_version "10.0")
	(general
		(thickness 1.6)
		(legacy_teardrops no)
	)
	(paper "A4")
	(title_block
		(title "12092022_DA0F0TMDCD0_F0T_Management_Board_D_brd_V3_OCP.brd")
		(comment 1 "Grand Teton / footprints 1269-1274 of 1440")
	)
	(layers
		(0 "F.Cu" signal "TOP")
		(4 "In1.Cu" signal "GND")
		(6 "In2.Cu" signal "IN1")
		(8 "In3.Cu" signal "GND1")
		(10 "In4.Cu" signal "IN2")
		(12 "In5.Cu" signal "VCC")
		(14 "In6.Cu" signal "VCC1")
		(16 "In7.Cu" signal "IN3")
		(18 "In8.Cu" signal "GND2")
		(20 "In9.Cu" signal "IN4")
		(22 "In10.Cu" signal "GND3")
		(2 "B.Cu" signal "BOTTOM")
		(9 "F.Adhes" user "F.Adhesive")
		(11 "B.Adhes" user "B.Adhesive")
		(13 "F.Paste" user "Package Geometry/Pastemask Top")
		(15 "B.Paste" user "Package Geometry/Pastemask Bottom")
		(5 "F.SilkS" user "Ref Des/Silkscreen Top")
		(7 "B.SilkS" user "Ref Des/Silkscreen Bottom")
		(1 "F.Mask" user "Board Geometry/Soldermask Top")
		(3 "B.Mask" user "Board Geometry/Soldermask Bottom")
		(17 "Dwgs.User" user "User.Drawings")
		(19 "Cmts.User" user "User.Comments")
		(21 "Eco1.User" user "User.Eco1")
		(23 "Eco2.User" user "User.Eco2")
		(25 "Edge.Cuts" user "Board Geometry/Outline")
		(27 "Margin" user)
		(31 "F.CrtYd" user "Package Geometry/Place Bound Top")
		(29 "B.CrtYd" user "Package Geometry/Place Bound Bottom")
		(35 "F.Fab" user "Ref Des/Assembly Top")
		(33 "B.Fab" user "Ref Des/Assembly Bottom")
	)
	(footprint ""
		(layer "B.Cu")
		(at 83.058 -101.473 90)
		(property "Reference" "C330"
			(at 0 0 90)
			(layer "B.SilkS")
			(hide yes)
			(effects
				(font
					(size 1.27 1.27)
				)
				(justify mirror)
			)
		)
		(property "Value" ""
			(at 0 0 90)
			(layer "B.Fab")
			(effects
				(font
					(size 1.27 1.27)
				)
				(justify mirror)
			)
		)
		(duplicate_pad_numbers_are_jumpers no)
		(fp_line
			(start 1.524 -0.762)
			(end -1.524 -0.762)
			(stroke
				(width 0.1524)
				(type default)
			)
			(layer "B.SilkS")
		)
		(fp_line
			(start -1.524 -0.762)
			(end -1.524 0.762)
			(stroke
				(width 0.1524)
				(type default)
			)
			(layer "B.SilkS")
		)
		(fp_line
			(start 1.524 0.762)
			(end 1.524 -0.762)
			(stroke
				(width 0.1524)
				(type default)
			)
			(layer "B.SilkS")
		)
		(fp_line
			(start -1.524 0.762)
			(end 1.524 0.762)
			(stroke
				(width 0.1524)
				(type default)
			)
			(layer "B.SilkS")
		)
		(fp_line
			(start 1.1049 -0.724916)
			(end 1.1049 0.724916)
			(stroke
				(width 0.1)
				(type default)
			)
			(layer "B.Fab")
		)
		(fp_line
			(start -1.1049 -0.724916)
			(end 1.1049 -0.724916)
			(stroke
				(width 0.1)
				(type default)
			)
			(layer "B.Fab")
		)
		(fp_line
			(start 1.1049 0.724916)
			(end -1.1049 0.724916)
			(stroke
				(width 0.1)
				(type default)
			)
			(layer "B.Fab")
		)
		(fp_line
			(start -1.1049 0.724916)
			(end -1.1049 -0.724916)
			(stroke
				(width 0.1)
				(type default)
			)
			(layer "B.Fab")
		)
		(pad "1" smd rect
			(at 0.889 0 90)
			(size 1.016 1.27)
			(layers "B.Cu" "B.Mask" "B.Paste")
			(net "P12V_AUX")
		)
		(pad "2" smd rect
			(at -0.889 0 90)
			(size 1.016 1.27)
			(layers "B.Cu" "B.Mask" "B.Paste")
			(net "GND")
		)
	)
	(footprint ""
		(layer "B.Cu")
		(at 51.2445 -88.7095 180)
		(property "Reference" "R703"
			(at 0 0 0)
			(layer "B.SilkS")
			(hide yes)
			(effects
				(font
					(size 1.27 1.27)
				)
				(justify mirror)
			)
		)
		(property "Value" ""
			(at 0 0 0)
			(layer "B.Fab")
			(effects
				(font
					(size 1.27 1.27)
				)
				(justify mirror)
			)
		)
		(duplicate_pad_numbers_are_jumpers no)
		(fp_line
			(start 0.7874 0.4064)
			(end 0.7874 -0.4064)
			(stroke
				(width 0.1524)
				(type default)
			)
			(layer "B.SilkS")
		)
		(fp_line
			(start 0.7874 -0.4064)
			(end -0.7874 -0.4064)
			(stroke
				(width 0.1524)
				(type default)
			)
			(layer "B.SilkS")
		)
		(fp_line
			(start -0.7874 0.4064)
			(end 0.7874 0.4064)
			(stroke
				(width 0.1524)
				(type default)
			)
			(layer "B.SilkS")
		)
		(fp_line
			(start -0.7874 -0.4064)
			(end -0.7874 0.4064)
			(stroke
				(width 0.1524)
				(type default)
			)
			(layer "B.SilkS")
		)
		(fp_line
			(start 0.67945 0.3048)
			(end 0.67945 -0.305054)
			(stroke
				(width 0.1)
				(type default)
			)
			(layer "B.Fab")
		)
		(fp_line
			(start 0.67945 -0.305054)
			(end 0.12065 -0.305054)
			(stroke
				(width 0.1)
				(type default)
			)
			(layer "B.Fab")
		)
		(fp_line
			(start 0.12065 0.3048)
			(end 0.67945 0.3048)
			(stroke
				(width 0.1)
				(type default)
			)
			(layer "B.Fab")
		)
		(fp_line
			(start 0.12065 0.2794)
			(end 0.12065 0.3048)
			(stroke
				(width 0.1)
				(type default)
			)
			(layer "B.Fab")
		)
		(fp_line
			(start 0.12065 -0.2794)
			(end -0.12065 -0.2794)
			(stroke
				(width 0.1)
				(type default)
			)
			(layer "B.Fab")
		)
		(fp_line
			(start 0.12065 -0.305054)
			(end 0.12065 -0.2794)
			(stroke
				(width 0.1)
				(type default)
			)
			(layer "B.Fab")
		)
		(fp_line
			(start -0.120396 0.3048)
			(end -0.120396 0.2794)
			(stroke
				(width 0.1)
				(type default)
			)
			(layer "B.Fab")
		)
		(fp_line
			(start -0.120396 0.2794)
			(end 0.12065 0.2794)
			(stroke
				(width 0.1)
				(type default)
			)
			(layer "B.Fab")
		)
		(fp_line
			(start -0.12065 -0.2794)
			(end -0.12065 -0.3048)
			(stroke
				(width 0.1)
				(type default)
			)
			(layer "B.Fab")
		)
		(fp_line
			(start -0.12065 -0.3048)
			(end -0.67945 -0.3048)
			(stroke
				(width 0.1)
				(type default)
			)
			(layer "B.Fab")
		)
		(fp_line
			(start -0.67945 0.3048)
			(end -0.120396 0.3048)
			(stroke
				(width 0.1)
				(type default)
			)
			(layer "B.Fab")
		)
		(fp_line
			(start -0.67945 -0.3048)
			(end -0.67945 0.3048)
			(stroke
				(width 0.1)
				(type default)
			)
			(layer "B.Fab")
		)
		(pad "1" smd circle
			(at 0.40005 0)
			(size 0 0)
			(layers "B.Cu" "B.Mask" "B.Paste")
			(net "PWRGD_DSW_PWROK")
		)
		(pad "2" smd circle
			(at -0.40005 0)
			(size 0 0)
			(layers "B.Cu" "B.Mask" "B.Paste")
			(net "PWRGD_DSW_PWROK_R3")
		)
	)
	(footprint ""
		(layer "B.Cu")
		(at 47.51578 -66.27114 90)
		(property "Reference" "R843"
			(at 0 0 90)
			(layer "B.SilkS")
			(hide yes)
			(effects
				(font
					(size 1.27 1.27)
				)
				(justify mirror)
			)
		)
		(property "Value" ""
			(at 0 0 90)
			(layer "B.Fab")
			(effects
				(font
					(size 1.27 1.27)
				)
				(justify mirror)
			)
		)
		(duplicate_pad_numbers_are_jumpers no)
		(fp_line
			(start 0.7874 -0.4064)
			(end -0.7874 -0.4064)
			(stroke
				(width 0.1524)
				(type default)
			)
			(layer "B.SilkS")
		)
		(fp_line
			(start -0.7874 -0.4064)
			(end -0.7874 0.4064)
			(stroke
				(width 0.1524)
				(type default)
			)
			(layer "B.SilkS")
		)
		(fp_line
			(start 0.7874 0.4064)
			(end 0.7874 -0.4064)
			(stroke
				(width 0.1524)
				(type default)
			)
			(layer "B.SilkS")
		)
		(fp_line
			(start -0.7874 0.4064)
			(end 0.7874 0.4064)
			(stroke
				(width 0.1524)
				(type default)
			)
			(layer "B.SilkS")
		)
		(fp_line
			(start 0.67945 -0.305054)
			(end 0.12065 -0.305054)
			(stroke
				(width 0.1)
				(type default)
			)
			(layer "B.Fab")
		)
		(fp_line
			(start 0.12065 -0.305054)
			(end 0.12065 -0.2794)
			(stroke
				(width 0.1)
				(type default)
			)
			(layer "B.Fab")
		)
		(fp_line
			(start -0.12065 -0.3048)
			(end -0.67945 -0.3048)
			(stroke
				(width 0.1)
				(type default)
			)
			(layer "B.Fab")
		)
		(fp_line
			(start -0.67945 -0.3048)
			(end -0.67945 0.3048)
			(stroke
				(width 0.1)
				(type default)
			)
			(layer "B.Fab")
		)
		(fp_line
			(start 0.12065 -0.2794)
			(end -0.12065 -0.2794)
			(stroke
				(width 0.1)
				(type default)
			)
			(layer "B.Fab")
		)
		(fp_line
			(start -0.12065 -0.2794)
			(end -0.12065 -0.3048)
			(stroke
				(width 0.1)
				(type default)
			)
			(layer "B.Fab")
		)
		(fp_line
			(start 0.12065 0.2794)
			(end 0.12065 0.3048)
			(stroke
				(width 0.1)
				(type default)
			)
			(layer "B.Fab")
		)
		(fp_line
			(start -0.120396 0.2794)
			(end 0.12065 0.2794)
			(stroke
				(width 0.1)
				(type default)
			)
			(layer "B.Fab")
		)
		(fp_line
			(start 0.67945 0.3048)
			(end 0.67945 -0.305054)
			(stroke
				(width 0.1)
				(type default)
			)
			(layer "B.Fab")
		)
		(fp_line
			(start 0.12065 0.3048)
			(end 0.67945 0.3048)
			(stroke
				(width 0.1)
				(type default)
			)
			(layer "B.Fab")
		)
		(fp_line
			(start -0.120396 0.3048)
			(end -0.120396 0.2794)
			(stroke
				(width 0.1)
				(type default)
			)
			(layer "B.Fab")
		)
		(fp_line
			(start -0.67945 0.3048)
			(end -0.120396 0.3048)
			(stroke
				(width 0.1)
				(type default)
			)
			(layer "B.Fab")
		)
		(pad "1" smd circle
			(at 0.40005 0 270)
			(size 0 0)
			(layers "B.Cu" "B.Mask" "B.Paste")
			(net "P3V3_AUX")
		)
		(pad "2" smd circle
			(at -0.40005 0 270)
			(size 0 0)
			(layers "B.Cu" "B.Mask" "B.Paste")
			(net "SMB_BMC_ALERT10_N")
		)
	)
	(footprint ""
		(layer "B.Cu")
		(at 38.3286 -4.1148 -90)
		(property "Reference" "U33"
			(at 0.924052 1.4986 0)
			(unlocked yes)
			(layer "B.SilkS")
			(effects
				(font
					(size 0.7874 0.5842)
					(thickness 0.1524)
				)
				(justify left mirror)
			)
		)
		(property "Value" ""
			(at 0 0 90)
			(layer "B.Fab")
			(effects
				(font
					(size 1.27 1.27)
				)
				(justify mirror)
			)
		)
		(duplicate_pad_numbers_are_jumpers no)
		(fp_line
			(start -1.3462 1.1938)
			(end -1.3462 -1.1938)
			(stroke
				(width 0.1524)
				(type default)
			)
			(layer "B.SilkS")
		)
		(fp_line
			(start 1.3462 1.1938)
			(end -1.3462 1.1938)
			(stroke
				(width 0.1524)
				(type default)
			)
			(layer "B.SilkS")
		)
		(fp_line
			(start -1.3462 -1.1938)
			(end 1.3462 -1.1938)
			(stroke
				(width 0.1524)
				(type default)
			)
			(layer "B.SilkS")
		)
		(fp_line
			(start 1.3462 -1.1938)
			(end 1.3462 1.1684)
			(stroke
				(width 0.1524)
				(type default)
			)
			(layer "B.SilkS")
		)
		(fp_poly
			(pts
				(xy 1.447038 -0.760476) (xy 2.052066 -0.457962) (xy 2.052066 -1.06299)
			)
			(stroke
				(width 0)
				(type default)
			)
			(fill yes)
			(layer "B.SilkS")
		)
		(fp_line
			(start -0.674878 1.124966)
			(end -0.674878 -1.124966)
			(stroke
				(width 0.1)
				(type default)
			)
			(layer "B.Fab")
		)
		(fp_line
			(start 0.674878 1.124966)
			(end -0.674878 1.124966)
			(stroke
				(width 0.1)
				(type default)
			)
			(layer "B.Fab")
		)
		(fp_line
			(start -0.674878 -1.124966)
			(end 0.674878 -1.124966)
			(stroke
				(width 0.1)
				(type default)
			)
			(layer "B.Fab")
		)
		(fp_line
			(start 0.674878 -1.124966)
			(end 0.674878 1.124966)
			(stroke
				(width 0.1)
				(type default)
			)
			(layer "B.Fab")
		)
		(fp_poly
			(pts
				(xy 1.447038 -0.760476) (xy 2.052066 -0.457962) (xy 2.052066 -1.06299)
			)
			(stroke
				(width 0)
				(type default)
			)
			(fill yes)
			(layer "B.Fab")
		)
		(pad "1" smd rect
			(at 0.899922 -0.750062 90)
			(size 0.6096 0.6096)
			(layers "B.Cu" "B.Mask" "B.Paste")
			(net "BMC_DDC_BUF_EN")
		)
		(pad "2" smd rect
			(at 0.899922 0)
			(size 0.4064 0.6096)
			(layers "B.Cu" "B.Mask" "B.Paste")
			(net "V_VGAHS")
		)
		(pad "3" smd rect
			(at 0.899922 0.750062 90)
			(size 0.6096 0.6096)
			(layers "B.Cu" "B.Mask" "B.Paste")
			(net "GND")
		)
		(pad "4" smd rect
			(at -0.899922 0.750062 90)
			(size 0.6096 0.6096)
			(layers "B.Cu" "B.Mask" "B.Paste")
			(net "V_VGAHS_BUF_R")
		)
		(pad "5" smd rect
			(at -0.899922 -0.750062 90)
			(size 0.6096 0.6096)
			(layers "B.Cu" "B.Mask" "B.Paste")
			(net "BMC_DDC_BUF_PWR")
		)
	)
	(footprint ""
		(layer "B.Cu")
		(at 38.47084 -35.828224)
		(property "Reference" "R208"
			(at 0 0 0)
			(layer "B.SilkS")
			(hide yes)
			(effects
				(font
					(size 1.27 1.27)
				)
				(justify mirror)
			)
		)
		(property "Value" ""
			(at 0 0 0)
			(layer "B.Fab")
			(effects
				(font
					(size 1.27 1.27)
				)
				(justify mirror)
			)
		)
		(duplicate_pad_numbers_are_jumpers no)
		(fp_line
			(start -0.7874 -0.4064)
			(end -0.7874 0.4064)
			(stroke
				(width 0.1524)
				(type default)
			)
			(layer "B.SilkS")
		)
		(fp_line
			(start -0.7874 0.4064)
			(end 0.7874 0.4064)
			(stroke
				(width 0.1524)
				(type default)
			)
			(layer "B.SilkS")
		)
		(fp_line
			(start 0.7874 -0.4064)
			(end -0.7874 -0.4064)
			(stroke
				(width 0.1524)
				(type default)
			)
			(layer "B.SilkS")
		)
		(fp_line
			(start 0.7874 0.4064)
			(end 0.7874 -0.4064)
			(stroke
				(width 0.1524)
				(type default)
			)
			(layer "B.SilkS")
		)
		(fp_line
			(start -0.67945 -0.3048)
			(end -0.67945 0.3048)
			(stroke
				(width 0.1)
				(type default)
			)
			(layer "B.Fab")
		)
		(fp_line
			(start -0.67945 0.3048)
			(end -0.120396 0.3048)
			(stroke
				(width 0.1)
				(type default)
			)
			(layer "B.Fab")
		)
		(fp_line
			(start -0.12065 -0.3048)
			(end -0.67945 -0.3048)
			(stroke
				(width 0.1)
				(type default)
			)
			(layer "B.Fab")
		)
		(fp_line
			(start -0.12065 -0.2794)
			(end -0.12065 -0.3048)
			(stroke
				(width 0.1)
				(type default)
			)
			(layer "B.Fab")
		)
		(fp_line
			(start -0.120396 0.2794)
			(end 0.12065 0.2794)
			(stroke
				(width 0.1)
				(type default)
			)
			(layer "B.Fab")
		)
		(fp_line
			(start -0.120396 0.3048)
			(end -0.120396 0.2794)
			(stroke
				(width 0.1)
				(type default)
			)
			(layer "B.Fab")
		)
		(fp_line
			(start 0.12065 -0.305054)
			(end 0.12065 -0.2794)
			(stroke
				(width 0.1)
				(type default)
			)
			(layer "B.Fab")
		)
		(fp_line
			(start 0.12065 -0.2794)
			(end -0.12065 -0.2794)
			(stroke
				(width 0.1)
				(type default)
			)
			(layer "B.Fab")
		)
		(fp_line
			(start 0.12065 0.2794)
			(end 0.12065 0.3048)
			(stroke
				(width 0.1)
				(type default)
			)
			(layer "B.Fab")
		)
		(fp_line
			(start 0.12065 0.3048)
			(end 0.67945 0.3048)
			(stroke
				(width 0.1)
				(type default)
			)
			(layer "B.Fab")
		)
		(fp_line
			(start 0.67945 -0.305054)
			(end 0.12065 -0.305054)
			(stroke
				(width 0.1)
				(type default)
			)
			(layer "B.Fab")
		)
		(fp_line
			(start 0.67945 0.3048)
			(end 0.67945 -0.305054)
			(stroke
				(width 0.1)
				(type default)
			)
			(layer "B.Fab")
		)
		(pad "1" smd circle
			(at 0.40005 0 180)
			(size 0 0)
			(layers "B.Cu" "B.Mask" "B.Paste")
			(net "P1V8_AUX")
		)
		(pad "2" smd circle
			(at -0.40005 0 180)
			(size 0 0)
			(layers "B.Cu" "B.Mask" "B.Paste")
			(net "P3V3_P1V8_SD1VDD")
		)
	)
	(footprint ""
		(layer "B.Cu")
		(at 41.918128 -60.573666)
		(property "Reference" "R225"
			(at 0 0 0)
			(layer "B.SilkS")
			(hide yes)
			(effects
				(font
					(size 1.27 1.27)
				)
				(justify mirror)
			)
		)
		(property "Value" ""
			(at 0 0 0)
			(layer "B.Fab")
			(effects
				(font
					(size 1.27 1.27)
				)
				(justify mirror)
			)
		)
		(duplicate_pad_numbers_are_jumpers no)
		(fp_line
			(start -0.7874 -0.4064)
			(end -0.7874 0.4064)
			(stroke
				(width 0.1524)
				(type default)
			)
			(layer "B.SilkS")
		)
		(fp_line
			(start -0.7874 0.4064)
			(end 0.7874 0.4064)
			(stroke
				(width 0.1524)
				(type default)
			)
			(layer "B.SilkS")
		)
		(fp_line
			(start 0.7874 -0.4064)
			(end -0.7874 -0.4064)
			(stroke
				(width 0.1524)
				(type default)
			)
			(layer "B.SilkS")
		)
		(fp_line
			(start 0.7874 0.4064)
			(end 0.7874 -0.4064)
			(stroke
				(width 0.1524)
				(type default)
			)
			(layer "B.SilkS")
		)
		(fp_line
			(start -0.67945 -0.3048)
			(end -0.67945 0.3048)
			(stroke
				(width 0.1)
				(type default)
			)
			(layer "B.Fab")
		)
		(fp_line
			(start -0.67945 0.3048)
			(end -0.120396 0.3048)
			(stroke
				(width 0.1)
				(type default)
			)
			(layer "B.Fab")
		)
		(fp_line
			(start -0.12065 -0.3048)
			(end -0.67945 -0.3048)
			(stroke
				(width 0.1)
				(type default)
			)
			(layer "B.Fab")
		)
		(fp_line
			(start -0.12065 -0.2794)
			(end -0.12065 -0.3048)
			(stroke
				(width 0.1)
				(type default)
			)
			(layer "B.Fab")
		)
		(fp_line
			(start -0.120396 0.2794)
			(end 0.12065 0.2794)
			(stroke
				(width 0.1)
				(type default)
			)
			(layer "B.Fab")
		)
		(fp_line
			(start -0.120396 0.3048)
			(end -0.120396 0.2794)
			(stroke
				(width 0.1)
				(type default)
			)
			(layer "B.Fab")
		)
		(fp_line
			(start 0.12065 -0.305054)
			(end 0.12065 -0.2794)
			(stroke
				(width 0.1)
				(type default)
			)
			(layer "B.Fab")
		)
		(fp_line
			(start 0.12065 -0.2794)
			(end -0.12065 -0.2794)
			(stroke
				(width 0.1)
				(type default)
			)
			(layer "B.Fab")
		)
		(fp_line
			(start 0.12065 0.2794)
			(end 0.12065 0.3048)
			(stroke
				(width 0.1)
				(type default)
			)
			(layer "B.Fab")
		)
		(fp_line
			(start 0.12065 0.3048)
			(end 0.67945 0.3048)
			(stroke
				(width 0.1)
				(type default)
			)
			(layer "B.Fab")
		)
		(fp_line
			(start 0.67945 -0.305054)
			(end 0.12065 -0.305054)
			(stroke
				(width 0.1)
				(type default)
			)
			(layer "B.Fab")
		)
		(fp_line
			(start 0.67945 0.3048)
			(end 0.67945 -0.305054)
			(stroke
				(width 0.1)
				(type default)
			)
			(layer "B.Fab")
		)
		(pad "1" smd circle
			(at 0.40005 0 180)
			(size 0 0)
			(layers "B.Cu" "B.Mask" "B.Paste")
			(net "FM_PWR_BTN")
		)
		(pad "2" smd circle
			(at -0.40005 0 180)
			(size 0 0)
			(layers "B.Cu" "B.Mask" "B.Paste")
			(net "PWR_BTN_BMC_N")
		)
	)
)
